# T6G (Grand Teton) — schematic netlist excerpt (pin names and nets, part order shuffled) for the footprints in the layout excerpt that follows; sources: Cadence DE-HDL packaged netlist, KiCad conversion of 04192023_DAF0TMB3IC0_F0TG_MB_C_brd_V02_OCP.brd

C3894  Q_CAP  22UF 4V 20% X6S  pkg C0402  page 68 : A = PVDDCR_SOC_P0 ; B = GND
PC135_6  Q_CAP  22UF 4V 20% X6S  pkg C0805  page 213 : A = PVDDCR_CPU0_P1 ; B = GND
C623  Q_CAP  0.1UF 10V 10% X7S  pkg C0201  page 290 : A = P0V9_CPU0_RT1_2A_2D ; B = GND

(kicad_pcb
	(version 20260206)
	(generator "pcbnew")
	(generator_version "10.0")
	(general
		(thickness 1.6)
		(legacy_teardrops no)
	)
	(paper "A4")
	(title_block
		(title "04192023_DAF0TMB3IC0_F0TG_MB_C_brd_V02_OCP.brd")
		(comment 1 "Grand Teton / footprints 5488-5490 of 8354")
	)
	(layers
		(0 "F.Cu" signal "TOP")
		(4 "In1.Cu" signal "GND")
		(6 "In2.Cu" signal "IN1")
		(8 "In3.Cu" signal "GND1")
		(10 "In4.Cu" signal "IN2")
		(12 "In5.Cu" signal "GND2")
		(14 "In6.Cu" signal "IN3")
		(16 "In7.Cu" signal "GND3")
		(18 "In8.Cu" signal "VCC")
		(20 "In9.Cu" signal "VCC1")
		(22 "In10.Cu" signal "GND4")
		(24 "In11.Cu" signal "IN4")
		(26 "In12.Cu" signal "GND5")
		(28 "In13.Cu" signal "IN5")
		(30 "In14.Cu" signal "GND6")
		(32 "In15.Cu" signal "IN6")
		(34 "In16.Cu" signal "GND7")
		(2 "B.Cu" signal "BOTTOM")
		(9 "F.Adhes" user "F.Adhesive")
		(11 "B.Adhes" user "B.Adhesive")
		(13 "F.Paste" user "Package Geometry/Pastemask Top")
		(15 "B.Paste" user "Package Geometry/Pastemask Bottom")
		(5 "F.SilkS" user "Ref Des/Silkscreen Top")
		(7 "B.SilkS" user "Ref Des/Silkscreen Bottom")
		(1 "F.Mask" user "Board Geometry/Soldermask Top")
		(3 "B.Mask" user "Board Geometry/Soldermask Bottom")
		(17 "Dwgs.User" user "User.Drawings")
		(19 "Cmts.User" user "User.Comments")
		(21 "Eco1.User" user "User.Eco1")
		(23 "Eco2.User" user "User.Eco2")
		(25 "Edge.Cuts" user "Board Geometry/Outline")
		(27 "Margin" user)
		(31 "F.CrtYd" user "Package Geometry/Place Bound Top")
		(29 "B.CrtYd" user "Package Geometry/Place Bound Bottom")
		(35 "F.Fab" user "Ref Des/Assembly Top")
		(33 "B.Fab" user "Ref Des/Assembly Bottom")
	)
	(footprint ""
		(layer "B.Cu")
		(at 365.328454 -253.43231)
		(property "Reference" "C3894"
			(at 0 0 0)
			(layer "B.SilkS")
			(hide yes)
			(effects
				(font
					(size 1.27 1.27)
				)
				(justify mirror)
			)
		)
		(property "Value" ""
			(at 0 0 0)
			(layer "B.Fab")
			(effects
				(font
					(size 1.27 1.27)
				)
				(justify mirror)
			)
		)
		(duplicate_pad_numbers_are_jumpers no)
		(fp_line
			(start -0.7874 -0.4064)
			(end -0.7874 0.4064)
			(stroke
				(width 0.1524)
				(type default)
			)
			(layer "B.SilkS")
		)
		(fp_line
			(start -0.7874 0.4064)
			(end 0.7874 0.4064)
			(stroke
				(width 0.1524)
				(type default)
			)
			(layer "B.SilkS")
		)
		(fp_line
			(start 0.7874 -0.4064)
			(end -0.7874 -0.4064)
			(stroke
				(width 0.1524)
				(type default)
			)
			(layer "B.SilkS")
		)
		(fp_line
			(start 0.7874 0.4064)
			(end 0.7874 -0.4064)
			(stroke
				(width 0.1524)
				(type default)
			)
			(layer "B.SilkS")
		)
		(fp_line
			(start -0.67945 -0.3048)
			(end -0.67945 0.3048)
			(stroke
				(width 0.1)
				(type default)
			)
			(layer "B.Fab")
		)
		(fp_line
			(start -0.67945 0.3048)
			(end -0.120396 0.3048)
			(stroke
				(width 0.1)
				(type default)
			)
			(layer "B.Fab")
		)
		(fp_line
			(start -0.12065 -0.3048)
			(end -0.67945 -0.3048)
			(stroke
				(width 0.1)
				(type default)
			)
			(layer "B.Fab")
		)
		(fp_line
			(start -0.12065 -0.2794)
			(end -0.12065 -0.3048)
			(stroke
				(width 0.1)
				(type default)
			)
			(layer "B.Fab")
		)
		(fp_line
			(start -0.120396 0.2794)
			(end 0.12065 0.2794)
			(stroke
				(width 0.1)
				(type default)
			)
			(layer "B.Fab")
		)
		(fp_line
			(start -0.120396 0.3048)
			(end -0.120396 0.2794)
			(stroke
				(width 0.1)
				(type default)
			)
			(layer "B.Fab")
		)
		(fp_line
			(start 0.12065 -0.305054)
			(end 0.12065 -0.2794)
			(stroke
				(width 0.1)
				(type default)
			)
			(layer "B.Fab")
		)
		(fp_line
			(start 0.12065 -0.2794)
			(end -0.12065 -0.2794)
			(stroke
				(width 0.1)
				(type default)
			)
			(layer "B.Fab")
		)
		(fp_line
			(start 0.12065 0.2794)
			(end 0.12065 0.3048)
			(stroke
				(width 0.1)
				(type default)
			)
			(layer "B.Fab")
		)
		(fp_line
			(start 0.12065 0.3048)
			(end 0.67945 0.3048)
			(stroke
				(width 0.1)
				(type default)
			)
			(layer "B.Fab")
		)
		(fp_line
			(start 0.67945 -0.305054)
			(end 0.12065 -0.305054)
			(stroke
				(width 0.1)
				(type default)
			)
			(layer "B.Fab")
		)
		(fp_line
			(start 0.67945 0.3048)
			(end 0.67945 -0.305054)
			(stroke
				(width 0.1)
				(type default)
			)
			(layer "B.Fab")
		)
		(pad "1" smd circle
			(at 0.40005 0 180)
			(size 0 0)
			(layers "B.Cu" "B.Mask" "B.Paste")
			(net "PVDDCR_SOC_P0")
		)
		(pad "2" smd circle
			(at -0.40005 0 180)
			(size 0 0)
			(layers "B.Cu" "B.Mask" "B.Paste")
			(net "GND")
		)
	)
	(footprint ""
		(layer "B.Cu")
		(at 65.825878 -177.349912 90)
		(property "Reference" "PC135_6"
			(at 0 0 90)
			(layer "B.SilkS")
			(hide yes)
			(effects
				(font
					(size 1.27 1.27)
				)
				(justify mirror)
			)
		)
		(property "Value" ""
			(at 0 0 90)
			(layer "B.Fab")
			(effects
				(font
					(size 1.27 1.27)
				)
				(justify mirror)
			)
		)
		(duplicate_pad_numbers_are_jumpers no)
		(fp_line
			(start 1.524 -0.762)
			(end -1.524 -0.762)
			(stroke
				(width 0.1524)
				(type default)
			)
			(layer "B.SilkS")
		)
		(fp_line
			(start -1.524 -0.762)
			(end -1.524 0.762)
			(stroke
				(width 0.1524)
				(type default)
			)
			(layer "B.SilkS")
		)
		(fp_line
			(start 1.524 0.762)
			(end 1.524 -0.762)
			(stroke
				(width 0.1524)
				(type default)
			)
			(layer "B.SilkS")
		)
		(fp_line
			(start -1.524 0.762)
			(end 1.524 0.762)
			(stroke
				(width 0.1524)
				(type default)
			)
			(layer "B.SilkS")
		)
		(fp_line
			(start 1.1049 -0.724916)
			(end 1.1049 0.724916)
			(stroke
				(width 0.1)
				(type default)
			)
			(layer "B.Fab")
		)
		(fp_line
			(start -1.1049 -0.724916)
			(end 1.1049 -0.724916)
			(stroke
				(width 0.1)
				(type default)
			)
			(layer "B.Fab")
		)
		(fp_line
			(start 1.1049 0.724916)
			(end -1.1049 0.724916)
			(stroke
				(width 0.1)
				(type default)
			)
			(layer "B.Fab")
		)
		(fp_line
			(start -1.1049 0.724916)
			(end -1.1049 -0.724916)
			(stroke
				(width 0.1)
				(type default)
			)
			(layer "B.Fab")
		)
		(pad "1" smd rect
			(at 0.889 0 90)
			(size 1.016 1.27)
			(layers "B.Cu" "B.Mask" "B.Paste")
			(net "PVDDCR_CPU0_P1")
		)
		(pad "2" smd rect
			(at -0.889 0 90)
			(size 1.016 1.27)
			(layers "B.Cu" "B.Mask" "B.Paste")
			(net "GND")
		)
	)
	(footprint ""
		(layer "B.Cu")
		(at 349.245936 -396.393162 -90)
		(property "Reference" "C623"
			(at 0 0 90)
			(layer "B.SilkS")
			(hide yes)
			(effects
				(font
					(size 1.27 1.27)
				)
				(justify mirror)
			)
		)
		(property "Value" ""
			(at 0 0 90)
			(layer "B.Fab")
			(effects
				(font
					(size 1.27 1.27)
				)
				(justify mirror)
			)
		)
		(duplicate_pad_numbers_are_jumpers no)
		(fp_line
			(start -0.299974 0.150114)
			(end 0.299974 0.150114)
			(stroke
				(width 0.1)
				(type default)
			)
			(layer "B.Fab")
		)
		(fp_line
			(start 0.299974 0.150114)
			(end 0.299974 -0.150114)
			(stroke
				(width 0.1)
				(type default)
			)
			(layer "B.Fab")
		)
		(fp_line
			(start -0.299974 -0.150114)
			(end -0.299974 0.150114)
			(stroke
				(width 0.1)
				(type default)
			)
			(layer "B.Fab")
		)
		(fp_line
			(start 0.299974 -0.150114)
			(end -0.299974 -0.150114)
			(stroke
				(width 0.1)
				(type default)
			)
			(layer "B.Fab")
		)
		(pad "1" smd rect
			(at 0.2667 0 90)
			(size 0.3048 0.381)
			(layers "B.Cu" "B.Mask" "B.Paste")
			(net "P0V9_CPU0_RT1_2A_2D")
		)
		(pad "2" smd rect
			(at -0.2667 0 90)
			(size 0.3048 0.381)
			(layers "B.Cu" "B.Mask" "B.Paste")
			(net "GND")
		)
	)
)
